(kicad_pcb
	(version 20260206)
	(generator "pcbnew")
	(generator_version "10.0")
	(general
		(thickness 1.6)
		(legacy_teardrops no)
	)
	(paper "A4")
	(title_block
		(title "panther-plus-userver — 13130-1b_20150205.brd")
		(comment 1 "Honey Badger (Wiwynn) / footprints 1395-1402 of 1509")
	)
	(layers
		(0 "F.Cu" signal "TOP")
		(4 "In1.Cu" signal "L2")
		(6 "In2.Cu" signal "L3")
		(8 "In3.Cu" signal "L4")
		(10 "In4.Cu" signal "L5")
		(12 "In5.Cu" signal "L6")
		(14 "In6.Cu" signal "L7")
		(16 "In7.Cu" signal "L8")
		(18 "In8.Cu" signal "L9")
		(20 "In9.Cu" signal "L10")
		(22 "In10.Cu" signal "L11")
		(2 "B.Cu" signal "BOTTOM")
		(9 "F.Adhes" user "F.Adhesive")
		(11 "B.Adhes" user "B.Adhesive")
		(13 "F.Paste" user "Package Geometry/Pastemask Top")
		(15 "B.Paste" user "Package Geometry/Pastemask Bottom")
		(5 "F.SilkS" user "Ref Des/Silkscreen Top")
		(7 "B.SilkS" user "Ref Des/Silkscreen Bottom")
		(1 "F.Mask" user "Board Geometry/Soldermask Top")
		(3 "B.Mask" user "Board Geometry/Soldermask Bottom")
		(17 "Dwgs.User" user "User.Drawings")
		(19 "Cmts.User" user "User.Comments")
		(21 "Eco1.User" user "User.Eco1")
		(23 "Eco2.User" user "User.Eco2")
		(25 "Edge.Cuts" user "Board Geometry/Outline")
		(27 "Margin" user)
		(31 "F.CrtYd" user "Package Geometry/Place Bound Top")
		(29 "B.CrtYd" user "Package Geometry/Place Bound Bottom")
		(35 "F.Fab" user "Ref Des/Assembly Top")
		(33 "B.Fab" user "Ref Des/Assembly Bottom")
	)
	(footprint ""
		(layer "B.Cu")
		(at 167.259 -12.600178 180)
		(property "Reference" "C340"
			(at 0 0 0)
			(layer "B.SilkS")
			(hide yes)
			(effects
				(font
					(size 1.27 1.27)
				)
				(justify mirror)
			)
		)
		(property "Value" "SCD1U16V2KX-3GP"
			(at -1.8923 -1.2065 180)
			(unlocked yes)
			(layer "B.Fab")
			(hide yes)
			(effects
				(font
					(size 1.016 1.016)
					(thickness 0.1524)
				)
				(justify mirror)
			)
		)
		(property "Device Type" "C402H22"
			(at -1.8923 -2.7305 180)
			(unlocked yes)
			(layer "B.Fab")
			(hide yes)
			(effects
				(font
					(size 1.016 1.016)
					(thickness 0.1524)
				)
				(justify mirror)
			)
		)
		(duplicate_pad_numbers_are_jumpers no)
		(fp_rect
			(start 0.381 0.7366)
			(end -0.381 -0.7366)
			(stroke
				(width 0)
				(type default)
			)
			(fill no)
			(layer "B.CrtYd")
		)
		(fp_rect
			(start 0.381 0.7366)
			(end -0.381 -0.7366)
			(stroke
				(width 0)
				(type default)
			)
			(fill no)
			(layer "B.Fab")
		)
		(pad "1" smd custom
			(at 0 -0.4572)
			(size 0.1143 0.1143)
			(layers "B.Cu" "B.Mask" "B.Paste")
			(net "PV_VDDR")
			(options
				(clearance outline)
				(anchor circle)
			)
			(primitives
				(gr_poly
					(pts
						(arc
							(start -0.254 0.1778)
							(mid -0.239121 0.213721)
							(end -0.2032 0.2286)
						)
						(arc
							(start 0.2032 0.2286)
							(mid 0.239121 0.213721)
							(end 0.254 0.1778)
						)
						(arc
							(start 0.254 -0.1778)
							(mid 0.239121 -0.213721)
							(end 0.2032 -0.2286)
						)
						(arc
							(start -0.2032 -0.2286)
							(mid -0.239121 -0.213721)
							(end -0.254 -0.1778)
						)
					)
					(width 0)
					(fill yes)
				)
			)
		)
		(pad "2" smd custom
			(at 0 0.4572)
			(size 0.1143 0.1143)
			(layers "B.Cu" "B.Mask" "B.Paste")
			(net "GND")
			(options
				(clearance outline)
				(anchor circle)
			)
			(primitives
				(gr_poly
					(pts
						(arc
							(start -0.254 0.1778)
							(mid -0.239121 0.213721)
							(end -0.2032 0.2286)
						)
						(arc
							(start 0.2032 0.2286)
							(mid 0.239121 0.213721)
							(end 0.254 0.1778)
						)
						(arc
							(start 0.254 -0.1778)
							(mid 0.239121 -0.213721)
							(end 0.2032 -0.2286)
						)
						(arc
							(start -0.2032 -0.2286)
							(mid -0.239121 -0.213721)
							(end -0.254 -0.1778)
						)
					)
					(width 0)
					(fill yes)
				)
			)
		)
	)
	(footprint ""
		(layer "B.Cu")
		(at 80.137 -63.246 180)
		(property "Reference" "R291"
			(at 0 0 0)
			(layer "B.SilkS")
			(hide yes)
			(effects
				(font
					(size 1.27 1.27)
				)
				(justify mirror)
			)
		)
		(property "Value" "220R2F-GP"
			(at -0.064008 -3.993896 180)
			(unlocked yes)
			(layer "B.Fab")
			(hide yes)
			(effects
				(font
					(size 1.016 1.016)
					(thickness 0.1524)
				)
				(justify mirror)
			)
		)
		(property "Device Type" "R402H16"
			(at -0.064008 -5.517896 180)
			(unlocked yes)
			(layer "B.Fab")
			(hide yes)
			(effects
				(font
					(size 1.016 1.016)
					(thickness 0.1524)
				)
				(justify mirror)
			)
		)
		(duplicate_pad_numbers_are_jumpers no)
		(fp_rect
			(start 0.381 0.8382)
			(end -0.381 -0.8382)
			(stroke
				(width 0)
				(type default)
			)
			(fill no)
			(layer "B.CrtYd")
		)
		(fp_rect
			(start 0.381 0.8382)
			(end -0.381 -0.8382)
			(stroke
				(width 0)
				(type default)
			)
			(fill no)
			(layer "B.Fab")
		)
		(pad "1" smd custom
			(at 0 -0.4318)
			(size 0.127 0.127)
			(layers "B.Cu" "B.Mask" "B.Paste")
			(net "SVID_ALERT#")
			(options
				(clearance outline)
				(anchor circle)
			)
			(primitives
				(gr_poly
					(pts
						(arc
							(start -0.2032 0.2794)
							(mid -0.239121 0.264521)
							(end -0.254 0.2286)
						)
						(arc
							(start -0.254 -0.2286)
							(mid -0.239121 -0.264521)
							(end -0.2032 -0.2794)
						)
						(arc
							(start 0.2032 -0.2794)
							(mid 0.239121 -0.264521)
							(end 0.254 -0.2286)
						)
						(arc
							(start 0.254 0.2286)
							(mid 0.239121 0.264521)
							(end 0.2032 0.2794)
						)
					)
					(width 0)
					(fill yes)
				)
			)
		)
		(pad "2" smd custom
			(at 0 0.4318)
			(size 0.127 0.127)
			(layers "B.Cu" "B.Mask" "B.Paste")
			(net "SVID_CPU_ALERT#")
			(options
				(clearance outline)
				(anchor circle)
			)
			(primitives
				(gr_poly
					(pts
						(arc
							(start -0.2032 0.2794)
							(mid -0.239121 0.264521)
							(end -0.254 0.2286)
						)
						(arc
							(start -0.254 -0.2286)
							(mid -0.239121 -0.264521)
							(end -0.2032 -0.2794)
						)
						(arc
							(start 0.2032 -0.2794)
							(mid 0.239121 -0.264521)
							(end 0.254 -0.2286)
						)
						(arc
							(start 0.254 0.2286)
							(mid 0.239121 0.264521)
							(end 0.2032 0.2794)
						)
					)
					(width 0)
					(fill yes)
				)
			)
		)
	)
	(footprint ""
		(layer "B.Cu")
		(at 189.103 -60.325)
		(property "Reference" "C107"
			(at 0 0 0)
			(layer "B.SilkS")
			(hide yes)
			(effects
				(font
					(size 1.27 1.27)
				)
				(justify mirror)
			)
		)
		(property "Value" "SCD1U16V2KX-3GP"
			(at -1.1811 -2.7051 0)
			(unlocked yes)
			(layer "B.Fab")
			(hide yes)
			(effects
				(font
					(size 1.016 1.016)
					(thickness 0.1524)
				)
				(justify mirror)
			)
		)
		(property "Device Type" "C402H22"
			(at -1.1811 -4.2291 0)
			(unlocked yes)
			(layer "B.Fab")
			(hide yes)
			(effects
				(font
					(size 1.016 1.016)
					(thickness 0.1524)
				)
				(justify mirror)
			)
		)
		(duplicate_pad_numbers_are_jumpers no)
		(fp_rect
			(start 0.381 0.7366)
			(end -0.381 -0.7366)
			(stroke
				(width 0)
				(type default)
			)
			(fill no)
			(layer "B.CrtYd")
		)
		(fp_rect
			(start 0.381 0.7366)
			(end -0.381 -0.7366)
			(stroke
				(width 0)
				(type default)
			)
			(fill no)
			(layer "B.Fab")
		)
		(pad "1" smd custom
			(at 0 -0.4572 180)
			(size 0.1143 0.1143)
			(layers "B.Cu" "B.Mask" "B.Paste")
			(net "DDR3_M_A_VREF_DQ0")
			(options
				(clearance outline)
				(anchor circle)
			)
			(primitives
				(gr_poly
					(pts
						(arc
							(start -0.254 0.1778)
							(mid -0.239121 0.213721)
							(end -0.2032 0.2286)
						)
						(arc
							(start 0.2032 0.2286)
							(mid 0.239121 0.213721)
							(end 0.254 0.1778)
						)
						(arc
							(start 0.254 -0.1778)
							(mid 0.239121 -0.213721)
							(end 0.2032 -0.2286)
						)
						(arc
							(start -0.2032 -0.2286)
							(mid -0.239121 -0.213721)
							(end -0.254 -0.1778)
						)
					)
					(width 0)
					(fill yes)
				)
			)
		)
		(pad "2" smd custom
			(at 0 0.4572 180)
			(size 0.1143 0.1143)
			(layers "B.Cu" "B.Mask" "B.Paste")
			(net "GND")
			(options
				(clearance outline)
				(anchor circle)
			)
			(primitives
				(gr_poly
					(pts
						(arc
							(start -0.254 0.1778)
							(mid -0.239121 0.213721)
							(end -0.2032 0.2286)
						)
						(arc
							(start 0.2032 0.2286)
							(mid 0.239121 0.213721)
							(end 0.254 0.1778)
						)
						(arc
							(start 0.254 -0.1778)
							(mid 0.239121 -0.213721)
							(end 0.2032 -0.2286)
						)
						(arc
							(start -0.2032 -0.2286)
							(mid -0.239121 -0.213721)
							(end -0.254 -0.1778)
						)
					)
					(width 0)
					(fill yes)
				)
			)
		)
	)
	(footprint ""
		(layer "B.Cu")
		(at 197.485 -32.893 -90)
		(property "Reference" "R151"
			(at 0 0 90)
			(layer "B.SilkS")
			(hide yes)
			(effects
				(font
					(size 1.27 1.27)
				)
				(justify mirror)
			)
		)
		(property "Value" "300R2F-GP"
			(at -1.7907 -1.1176 270)
			(unlocked yes)
			(layer "B.Fab")
			(hide yes)
			(effects
				(font
					(size 1.016 1.016)
					(thickness 0.1524)
				)
				(justify mirror)
			)
		)
		(property "Device Type" "R402H16"
			(at -1.7907 -2.6416 270)
			(unlocked yes)
			(layer "B.Fab")
			(hide yes)
			(effects
				(font
					(size 1.016 1.016)
					(thickness 0.1524)
				)
				(justify mirror)
			)
		)
		(duplicate_pad_numbers_are_jumpers no)
		(fp_rect
			(start 0.381 0.8382)
			(end -0.381 -0.8382)
			(stroke
				(width 0)
				(type default)
			)
			(fill no)
			(layer "B.CrtYd")
		)
		(fp_rect
			(start 0.381 0.8382)
			(end -0.381 -0.8382)
			(stroke
				(width 0)
				(type default)
			)
			(fill no)
			(layer "B.Fab")
		)
		(pad "1" smd custom
			(at 0 -0.4318 90)
			(size 0.127 0.127)
			(layers "B.Cu" "B.Mask" "B.Paste")
			(net "PORT80_R_BIT2")
			(options
				(clearance outline)
				(anchor circle)
			)
			(primitives
				(gr_poly
					(pts
						(arc
							(start -0.2032 0.2794)
							(mid -0.239121 0.264521)
							(end -0.254 0.2286)
						)
						(arc
							(start -0.254 -0.2286)
							(mid -0.239121 -0.264521)
							(end -0.2032 -0.2794)
						)
						(arc
							(start 0.2032 -0.2794)
							(mid 0.239121 -0.264521)
							(end 0.254 -0.2286)
						)
						(arc
							(start 0.254 0.2286)
							(mid 0.239121 0.264521)
							(end 0.2032 0.2794)
						)
					)
					(width 0)
					(fill yes)
				)
			)
		)
		(pad "2" smd custom
			(at 0 0.4318 90)
			(size 0.127 0.127)
			(layers "B.Cu" "B.Mask" "B.Paste")
			(net "P3V3_STBY")
			(options
				(clearance outline)
				(anchor circle)
			)
			(primitives
				(gr_poly
					(pts
						(arc
							(start -0.2032 0.2794)
							(mid -0.239121 0.264521)
							(end -0.254 0.2286)
						)
						(arc
							(start -0.254 -0.2286)
							(mid -0.239121 -0.264521)
							(end -0.2032 -0.2794)
						)
						(arc
							(start 0.2032 -0.2794)
							(mid 0.239121 -0.264521)
							(end 0.254 -0.2286)
						)
						(arc
							(start 0.254 0.2286)
							(mid 0.239121 0.264521)
							(end 0.2032 0.2794)
						)
					)
					(width 0)
					(fill yes)
				)
			)
		)
	)
	(footprint ""
		(layer "B.Cu")
		(at 68.453 -61.595)
		(property "Reference" "R495"
			(at 0 0 0)
			(layer "B.SilkS")
			(hide yes)
			(effects
				(font
					(size 1.27 1.27)
				)
				(justify mirror)
			)
		)
		(property "Value" "2K2R2F-GP"
			(at -1.7907 -1.1176 0)
			(unlocked yes)
			(layer "B.Fab")
			(hide yes)
			(effects
				(font
					(size 1.016 1.016)
					(thickness 0.1524)
				)
				(justify mirror)
			)
		)
		(property "Device Type" "R402H16"
			(at -1.7907 -2.6416 0)
			(unlocked yes)
			(layer "B.Fab")
			(hide yes)
			(effects
				(font
					(size 1.016 1.016)
					(thickness 0.1524)
				)
				(justify mirror)
			)
		)
		(duplicate_pad_numbers_are_jumpers no)
		(fp_rect
			(start 0.381 0.8382)
			(end -0.381 -0.8382)
			(stroke
				(width 0)
				(type default)
			)
			(fill no)
			(layer "B.CrtYd")
		)
		(fp_rect
			(start 0.381 0.8382)
			(end -0.381 -0.8382)
			(stroke
				(width 0)
				(type default)
			)
			(fill no)
			(layer "B.Fab")
		)
		(pad "1" smd custom
			(at 0 -0.4318 180)
			(size 0.127 0.127)
			(layers "B.Cu" "B.Mask" "B.Paste")
			(net "P12V_SENSE")
			(options
				(clearance outline)
				(anchor circle)
			)
			(primitives
				(gr_poly
					(pts
						(arc
							(start -0.2032 0.2794)
							(mid -0.239121 0.264521)
							(end -0.254 0.2286)
						)
						(arc
							(start -0.254 -0.2286)
							(mid -0.239121 -0.264521)
							(end -0.2032 -0.2794)
						)
						(arc
							(start 0.2032 -0.2794)
							(mid 0.239121 -0.264521)
							(end 0.254 -0.2286)
						)
						(arc
							(start 0.254 0.2286)
							(mid 0.239121 0.264521)
							(end 0.2032 0.2794)
						)
					)
					(width 0)
					(fill yes)
				)
			)
		)
		(pad "2" smd custom
			(at 0 0.4318 180)
			(size 0.127 0.127)
			(layers "B.Cu" "B.Mask" "B.Paste")
			(net "GND")
			(options
				(clearance outline)
				(anchor circle)
			)
			(primitives
				(gr_poly
					(pts
						(arc
							(start -0.2032 0.2794)
							(mid -0.239121 0.264521)
							(end -0.254 0.2286)
						)
						(arc
							(start -0.254 -0.2286)
							(mid -0.239121 -0.264521)
							(end -0.2032 -0.2794)
						)
						(arc
							(start 0.2032 -0.2794)
							(mid 0.239121 -0.264521)
							(end 0.254 -0.2286)
						)
						(arc
							(start 0.254 0.2286)
							(mid 0.239121 0.264521)
							(end 0.2032 0.2794)
						)
					)
					(width 0)
					(fill yes)
				)
			)
		)
	)
	(footprint ""
		(layer "B.Cu")
		(at 75.565 -57.912 -90)
		(property "Reference" "R136"
			(at 0 0 90)
			(layer "B.SilkS")
			(hide yes)
			(effects
				(font
					(size 1.27 1.27)
				)
				(justify mirror)
			)
		)
		(property "Value" "0R2J-2-GP"
			(at -0.064008 -3.993896 270)
			(unlocked yes)
			(layer "B.Fab")
			(hide yes)
			(effects
				(font
					(size 1.016 1.016)
					(thickness 0.1524)
				)
				(justify mirror)
			)
		)
		(property "Device Type" "R402H16"
			(at -0.064008 -5.517896 270)
			(unlocked yes)
			(layer "B.Fab")
			(hide yes)
			(effects
				(font
					(size 1.016 1.016)
					(thickness 0.1524)
				)
				(justify mirror)
			)
		)
		(duplicate_pad_numbers_are_jumpers no)
		(fp_rect
			(start 0.381 0.8382)
			(end -0.381 -0.8382)
			(stroke
				(width 0)
				(type default)
			)
			(fill no)
			(layer "B.CrtYd")
		)
		(fp_rect
			(start 0.381 0.8382)
			(end -0.381 -0.8382)
			(stroke
				(width 0)
				(type default)
			)
			(fill no)
			(layer "B.Fab")
		)
		(pad "1" smd custom
			(at 0 -0.4318 90)
			(size 0.127 0.127)
			(layers "B.Cu" "B.Mask" "B.Paste")
			(net "VOL1_SEN_CLK")
			(options
				(clearance outline)
				(anchor circle)
			)
			(primitives
				(gr_poly
					(pts
						(arc
							(start -0.2032 0.2794)
							(mid -0.239121 0.264521)
							(end -0.254 0.2286)
						)
						(arc
							(start -0.254 -0.2286)
							(mid -0.239121 -0.264521)
							(end -0.2032 -0.2794)
						)
						(arc
							(start 0.2032 -0.2794)
							(mid 0.239121 -0.264521)
							(end 0.254 -0.2286)
						)
						(arc
							(start 0.254 0.2286)
							(mid 0.239121 0.264521)
							(end 0.2032 0.2794)
						)
					)
					(width 0)
					(fill yes)
				)
			)
		)
		(pad "2" smd custom
			(at 0 0.4318 90)
			(size 0.127 0.127)
			(layers "B.Cu" "B.Mask" "B.Paste")
			(net "SMB_HOST_LV_CLK")
			(options
				(clearance outline)
				(anchor circle)
			)
			(primitives
				(gr_poly
					(pts
						(arc
							(start -0.2032 0.2794)
							(mid -0.239121 0.264521)
							(end -0.254 0.2286)
						)
						(arc
							(start -0.254 -0.2286)
							(mid -0.239121 -0.264521)
							(end -0.2032 -0.2794)
						)
						(arc
							(start 0.2032 -0.2794)
							(mid 0.239121 -0.264521)
							(end 0.254 -0.2286)
						)
						(arc
							(start 0.254 0.2286)
							(mid 0.239121 0.264521)
							(end 0.2032 0.2794)
						)
					)
					(width 0)
					(fill yes)
				)
			)
		)
	)
	(footprint ""
		(layer "B.Cu")
		(at 204.1398 -39.4462 90)
		(property "Reference" "C351"
			(at 0 0 90)
			(layer "B.SilkS")
			(hide yes)
			(effects
				(font
					(size 1.27 1.27)
				)
				(justify mirror)
			)
		)
		(property "Value" "SCD1U16V2KX-3GP"
			(at -1.8923 -1.2065 90)
			(unlocked yes)
			(layer "B.Fab")
			(hide yes)
			(effects
				(font
					(size 1.016 1.016)
					(thickness 0.1524)
				)
				(justify mirror)
			)
		)
		(property "Device Type" "C402H22"
			(at -1.8923 -2.7305 90)
			(unlocked yes)
			(layer "B.Fab")
			(hide yes)
			(effects
				(font
					(size 1.016 1.016)
					(thickness 0.1524)
				)
				(justify mirror)
			)
		)
		(duplicate_pad_numbers_are_jumpers no)
		(fp_rect
			(start 0.381 0.7366)
			(end -0.381 -0.7366)
			(stroke
				(width 0)
				(type default)
			)
			(fill no)
			(layer "B.CrtYd")
		)
		(fp_rect
			(start 0.381 0.7366)
			(end -0.381 -0.7366)
			(stroke
				(width 0)
				(type default)
			)
			(fill no)
			(layer "B.Fab")
		)
		(pad "1" smd custom
			(at 0 -0.4572 270)
			(size 0.1143 0.1143)
			(layers "B.Cu" "B.Mask" "B.Paste")
			(net "PV_VDDR")
			(options
				(clearance outline)
				(anchor circle)
			)
			(primitives
				(gr_poly
					(pts
						(arc
							(start -0.254 0.1778)
							(mid -0.239121 0.213721)
							(end -0.2032 0.2286)
						)
						(arc
							(start 0.2032 0.2286)
							(mid 0.239121 0.213721)
							(end 0.254 0.1778)
						)
						(arc
							(start 0.254 -0.1778)
							(mid 0.239121 -0.213721)
							(end 0.2032 -0.2286)
						)
						(arc
							(start -0.2032 -0.2286)
							(mid -0.239121 -0.213721)
							(end -0.254 -0.1778)
						)
					)
					(width 0)
					(fill yes)
				)
			)
		)
		(pad "2" smd custom
			(at 0 0.4572 270)
			(size 0.1143 0.1143)
			(layers "B.Cu" "B.Mask" "B.Paste")
			(net "GND")
			(options
				(clearance outline)
				(anchor circle)
			)
			(primitives
				(gr_poly
					(pts
						(arc
							(start -0.254 0.1778)
							(mid -0.239121 0.213721)
							(end -0.2032 0.2286)
						)
						(arc
							(start 0.2032 0.2286)
							(mid 0.239121 0.213721)
							(end 0.254 0.1778)
						)
						(arc
							(start 0.254 -0.1778)
							(mid 0.239121 -0.213721)
							(end 0.2032 -0.2286)
						)
						(arc
							(start -0.2032 -0.2286)
							(mid -0.239121 -0.213721)
							(end -0.254 -0.1778)
						)
					)
					(width 0)
					(fill yes)
				)
			)
		)
	)
	(footprint ""
		(layer "B.Cu")
		(at 95.123 -33.782)
		(property "Reference" "C216"
			(at 0 0 0)
			(layer "B.SilkS")
			(hide yes)
			(effects
				(font
					(size 1.27 1.27)
				)
				(justify mirror)
			)
		)
		(property "Value" "SC1U10V2KX-1GP"
			(at -1.1811 -2.7051 0)
			(unlocked yes)
			(layer "B.Fab")
			(hide yes)
			(effects
				(font
					(size 1.016 1.016)
					(thickness 0.1524)
				)
				(justify mirror)
			)
		)
		(property "Device Type" "C402H22"
			(at -1.1811 -4.2291 0)
			(unlocked yes)
			(layer "B.Fab")
			(hide yes)
			(effects
				(font
					(size 1.016 1.016)
					(thickness 0.1524)
				)
				(justify mirror)
			)
		)
		(duplicate_pad_numbers_are_jumpers no)
		(fp_rect
			(start 0.381 0.7366)
			(end -0.381 -0.7366)
			(stroke
				(width 0)
				(type default)
			)
			(fill no)
			(layer "B.CrtYd")
		)
		(fp_rect
			(start 0.381 0.7366)
			(end -0.381 -0.7366)
			(stroke
				(width 0)
				(type default)
			)
			(fill no)
			(layer "B.Fab")
		)
		(pad "1" smd custom
			(at 0 -0.4572 180)
			(size 0.1143 0.1143)
			(layers "B.Cu" "B.Mask" "B.Paste")
			(net "P1V35")
			(options
				(clearance outline)
				(anchor circle)
			)
			(primitives
				(gr_poly
					(pts
						(arc
							(start -0.254 0.1778)
							(mid -0.239121 0.213721)
							(end -0.2032 0.2286)
						)
						(arc
							(start 0.2032 0.2286)
							(mid 0.239121 0.213721)
							(end 0.254 0.1778)
						)
						(arc
							(start 0.254 -0.1778)
							(mid 0.239121 -0.213721)
							(end 0.2032 -0.2286)
						)
						(arc
							(start -0.2032 -0.2286)
							(mid -0.239121 -0.213721)
							(end -0.254 -0.1778)
						)
					)
					(width 0)
					(fill yes)
				)
			)
		)
		(pad "2" smd custom
			(at 0 0.4572 180)
			(size 0.1143 0.1143)
			(layers "B.Cu" "B.Mask" "B.Paste")
			(net "GND")
			(options
				(clearance outline)
				(anchor circle)
			)
			(primitives
				(gr_poly
					(pts
						(arc
							(start -0.254 0.1778)
							(mid -0.239121 0.213721)
							(end -0.2032 0.2286)
						)
						(arc
							(start 0.2032 0.2286)
							(mid 0.239121 0.213721)
							(end 0.254 0.1778)
						)
						(arc
							(start 0.254 -0.1778)
							(mid 0.239121 -0.213721)
							(end 0.2032 -0.2286)
						)
						(arc
							(start -0.2032 -0.2286)
							(mid -0.239121 -0.213721)
							(end -0.254 -0.1778)
						)
					)
					(width 0)
					(fill yes)
				)
			)
		)
	)
)
